(kicad_pcb
	(version 20260206)
	(generator "pcbnew")
	(generator_version "10.0")
	(general
		(thickness 1.6)
		(legacy_teardrops no)
	)
	(paper "A4")
	(title_block
		(title "Bryce Canyon_R.DPB_16317-1_OCP.brd")
		(comment 1 "Bryce Canyon / footprints 1610-1618 of 2099")
	)
	(layers
		(0 "F.Cu" signal "TOP")
		(4 "In1.Cu" signal "L2GND")
		(6 "In2.Cu" signal "L3")
		(8 "In3.Cu" signal "L4VCC")
		(10 "In4.Cu" signal "L5VCC")
		(12 "In5.Cu" signal "L6")
		(14 "In6.Cu" signal "L7GND")
		(2 "B.Cu" signal "BOTTOM")
		(9 "F.Adhes" user "F.Adhesive")
		(11 "B.Adhes" user "B.Adhesive")
		(13 "F.Paste" user "Package Geometry/Pastemask Top")
		(15 "B.Paste" user "Package Geometry/Pastemask Bottom")
		(5 "F.SilkS" user "Ref Des/Silkscreen Top")
		(7 "B.SilkS" user "Ref Des/Silkscreen Bottom")
		(1 "F.Mask" user "Board Geometry/Soldermask Top")
		(3 "B.Mask" user "Board Geometry/Soldermask Bottom")
		(17 "Dwgs.User" user "User.Drawings")
		(19 "Cmts.User" user "User.Comments")
		(21 "Eco1.User" user "User.Eco1")
		(23 "Eco2.User" user "User.Eco2")
		(25 "Edge.Cuts" user "Board Geometry/Outline")
		(27 "Margin" user)
		(31 "F.CrtYd" user "Package Geometry/Place Bound Top")
		(29 "B.CrtYd" user "Package Geometry/Place Bound Bottom")
		(35 "F.Fab" user "Ref Des/Assembly Top")
		(33 "B.Fab" user "Ref Des/Assembly Bottom")
	)
	(footprint ""
		(layer "F.Cu")
		(at 161.544 -263.144 -90)
		(property "Reference" "R223"
			(at 0 0 270)
			(layer "F.SilkS")
			(hide yes)
			(effects
				(font
					(size 1.27 1.27)
				)
			)
		)
		(property "Value" "10KR2F-2-GP"
			(at 0.064008 -3.993896 270)
			(unlocked yes)
			(layer "F.Fab")
			(hide yes)
			(effects
				(font
					(size 1.016 1.016)
					(thickness 0.1524)
				)
			)
		)
		(property "Device Type" "R402H16"
			(at 0.064008 -5.517896 270)
			(unlocked yes)
			(layer "F.Fab")
			(hide yes)
			(effects
				(font
					(size 1.016 1.016)
					(thickness 0.1524)
				)
			)
		)
		(duplicate_pad_numbers_are_jumpers no)
		(fp_line
			(start -0.508 -0.9398)
			(end -0.508 0.9398)
			(stroke
				(width 0.1524)
				(type default)
			)
			(layer "F.SilkS")
		)
		(fp_line
			(start 0.508 -0.9398)
			(end -0.508 -0.9398)
			(stroke
				(width 0.1524)
				(type default)
			)
			(layer "F.SilkS")
		)
		(fp_rect
			(start -0.508 0.9398)
			(end 0.508 -0.9398)
			(stroke
				(width 0)
				(type default)
			)
			(fill no)
			(layer "F.CrtYd")
		)
		(fp_rect
			(start -0.508 0.9398)
			(end 0.508 -0.9398)
			(stroke
				(width 0)
				(type default)
			)
			(fill no)
			(layer "F.Fab")
		)
		(pad "1" smd custom
			(at 0 -0.4445 270)
			(size 0.1397 0.1397)
			(layers "F.Cu" "F.Mask" "F.Paste")
			(net "P3V3_STBY_B")
			(options
				(clearance outline)
				(anchor circle)
			)
			(primitives
				(gr_poly
					(pts
						(arc
							(start -0.1778 -0.2794)
							(mid -0.249642 -0.249642)
							(end -0.2794 -0.1778)
						)
						(arc
							(start -0.2794 0.1778)
							(mid -0.249642 0.249642)
							(end -0.1778 0.2794)
						)
						(arc
							(start 0.1778 0.2794)
							(mid 0.249642 0.249642)
							(end 0.2794 0.1778)
						)
						(arc
							(start 0.2794 -0.1778)
							(mid 0.249642 -0.249642)
							(end 0.1778 -0.2794)
						)
					)
					(width 0)
					(fill yes)
				)
			)
		)
		(pad "2" smd custom
			(at 0 0.4445 270)
			(size 0.1397 0.1397)
			(layers "F.Cu" "F.Mask" "F.Paste")
			(net "HDD_PRSNT_4")
			(options
				(clearance outline)
				(anchor circle)
			)
			(primitives
				(gr_poly
					(pts
						(arc
							(start -0.1778 -0.2794)
							(mid -0.249642 -0.249642)
							(end -0.2794 -0.1778)
						)
						(arc
							(start -0.2794 0.1778)
							(mid -0.249642 0.249642)
							(end -0.1778 0.2794)
						)
						(arc
							(start 0.1778 0.2794)
							(mid 0.249642 0.249642)
							(end 0.2794 0.1778)
						)
						(arc
							(start 0.2794 -0.1778)
							(mid 0.249642 -0.249642)
							(end 0.1778 -0.2794)
						)
					)
					(width 0)
					(fill yes)
				)
			)
		)
	)
	(footprint ""
		(layer "F.Cu")
		(at 192.513966 -269.705074)
		(property "Reference" "TP46"
			(at 0 0 0)
			(layer "F.SilkS")
			(hide yes)
			(effects
				(font
					(size 1.27 1.27)
				)
			)
		)
		(property "Value" "*"
			(at -0.0508 -1.6764 0)
			(unlocked yes)
			(layer "F.Fab")
			(hide yes)
			(effects
				(font
					(size 1.016 1.016)
					(thickness 0.1524)
				)
			)
		)
		(property "Device Type" "TPAD32"
			(at -0.0508 -3.2004 0)
			(unlocked yes)
			(layer "F.Fab")
			(hide yes)
			(effects
				(font
					(size 1.016 1.016)
					(thickness 0.1524)
				)
			)
		)
		(duplicate_pad_numbers_are_jumpers no)
		(fp_poly
			(pts
				(arc
					(start 0.4064 0)
					(mid -0.4064 0)
					(end 0.4064 0)
				)
			)
			(stroke
				(width 0)
				(type default)
			)
			(fill no)
			(layer "F.CrtYd")
		)
		(fp_poly
			(pts
				(arc
					(start 0.7112 0)
					(mid -0.7112 0)
					(end 0.7112 0)
				)
			)
			(stroke
				(width 0)
				(type default)
			)
			(fill no)
			(layer "F.Fab")
		)
		(pad "1" smd circle
			(at 0 0)
			(size 0.8128 0.8128)
			(layers "F.Cu" "F.Mask" "F.Paste")
			(net "ACT_HDD_5")
		)
	)
	(footprint ""
		(layer "F.Cu")
		(at 416.3314 -261.6454)
		(property "Reference" "C154"
			(at 0 0 0)
			(layer "F.SilkS")
			(hide yes)
			(effects
				(font
					(size 1.27 1.27)
				)
			)
		)
		(property "Value" "SCD01U50V2KX-1GP"
			(at 1.1811 -2.7051 0)
			(unlocked yes)
			(layer "F.Fab")
			(hide yes)
			(effects
				(font
					(size 1.016 1.016)
					(thickness 0.1524)
				)
			)
		)
		(property "Device Type" "C402H22"
			(at 1.1811 -4.2291 0)
			(unlocked yes)
			(layer "F.Fab")
			(hide yes)
			(effects
				(font
					(size 1.016 1.016)
					(thickness 0.1524)
				)
			)
		)
		(duplicate_pad_numbers_are_jumpers no)
		(fp_rect
			(start -0.4318 0.9525)
			(end 0.4318 -0.9525)
			(stroke
				(width 0)
				(type default)
			)
			(fill no)
			(layer "F.CrtYd")
		)
		(fp_rect
			(start -0.4318 0.9525)
			(end 0.4318 -0.9525)
			(stroke
				(width 0)
				(type default)
			)
			(fill no)
			(layer "F.Fab")
		)
		(pad "1" smd custom
			(at 0 -0.4445)
			(size 0.1524 0.1524)
			(layers "F.Cu" "F.Mask" "F.Paste")
			(net "HDD_PRSNT_9")
			(options
				(clearance outline)
				(anchor circle)
			)
			(primitives
				(gr_poly
					(pts
						(arc
							(start 0.3048 -0.2032)
							(mid 0.275042 -0.275042)
							(end 0.2032 -0.3048)
						)
						(arc
							(start -0.2032 -0.3048)
							(mid -0.275042 -0.275042)
							(end -0.3048 -0.2032)
						)
						(arc
							(start -0.3048 0.2032)
							(mid -0.275042 0.275042)
							(end -0.2032 0.3048)
						)
						(arc
							(start 0.2032 0.3048)
							(mid 0.275042 0.275042)
							(end 0.3048 0.2032)
						)
					)
					(width 0)
					(fill yes)
				)
			)
		)
		(pad "2" smd custom
			(at 0 0.4445)
			(size 0.1524 0.1524)
			(layers "F.Cu" "F.Mask" "F.Paste")
			(net "GND")
			(options
				(clearance outline)
				(anchor circle)
			)
			(primitives
				(gr_poly
					(pts
						(arc
							(start 0.3048 -0.2032)
							(mid 0.275042 -0.275042)
							(end 0.2032 -0.3048)
						)
						(arc
							(start -0.2032 -0.3048)
							(mid -0.275042 -0.275042)
							(end -0.3048 -0.2032)
						)
						(arc
							(start -0.3048 0.2032)
							(mid -0.275042 0.275042)
							(end -0.2032 0.3048)
						)
						(arc
							(start 0.2032 0.3048)
							(mid 0.275042 0.275042)
							(end 0.3048 0.2032)
						)
					)
					(width 0)
					(fill yes)
				)
			)
		)
	)
	(footprint ""
		(layer "F.Cu")
		(at 240.665 -311.912)
		(property "Reference" "R1085"
			(at 0 0 0)
			(layer "F.SilkS")
			(hide yes)
			(effects
				(font
					(size 1.27 1.27)
				)
			)
		)
		(property "Value" "4K7R2F-GP"
			(at 0.064008 -3.993896 0)
			(unlocked yes)
			(layer "F.Fab")
			(hide yes)
			(effects
				(font
					(size 1.016 1.016)
					(thickness 0.1524)
				)
			)
		)
		(property "Device Type" "R402H16"
			(at 0.064008 -5.517896 0)
			(unlocked yes)
			(layer "F.Fab")
			(hide yes)
			(effects
				(font
					(size 1.016 1.016)
					(thickness 0.1524)
				)
			)
		)
		(duplicate_pad_numbers_are_jumpers no)
		(fp_line
			(start -0.508 -0.9398)
			(end -0.508 0.9398)
			(stroke
				(width 0.1524)
				(type default)
			)
			(layer "F.SilkS")
		)
		(fp_line
			(start 0.508 -0.9398)
			(end -0.508 -0.9398)
			(stroke
				(width 0.1524)
				(type default)
			)
			(layer "F.SilkS")
		)
		(fp_rect
			(start -0.508 0.9398)
			(end 0.508 -0.9398)
			(stroke
				(width 0)
				(type default)
			)
			(fill no)
			(layer "F.CrtYd")
		)
		(fp_rect
			(start -0.508 0.9398)
			(end 0.508 -0.9398)
			(stroke
				(width 0)
				(type default)
			)
			(fill no)
			(layer "F.Fab")
		)
		(pad "1" smd custom
			(at 0 -0.4445)
			(size 0.1397 0.1397)
			(layers "F.Cu" "F.Mask" "F.Paste")
			(net "P3V3_STBY_A")
			(options
				(clearance outline)
				(anchor circle)
			)
			(primitives
				(gr_poly
					(pts
						(arc
							(start -0.1778 -0.2794)
							(mid -0.249642 -0.249642)
							(end -0.2794 -0.1778)
						)
						(arc
							(start -0.2794 0.1778)
							(mid -0.249642 0.249642)
							(end -0.1778 0.2794)
						)
						(arc
							(start 0.1778 0.2794)
							(mid 0.249642 0.249642)
							(end 0.2794 0.1778)
						)
						(arc
							(start 0.2794 -0.1778)
							(mid 0.249642 -0.249642)
							(end 0.1778 -0.2794)
						)
					)
					(width 0)
					(fill yes)
				)
			)
		)
		(pad "2" smd custom
			(at 0 0.4445)
			(size 0.1397 0.1397)
			(layers "F.Cu" "F.Mask" "F.Paste")
			(net "MAX31790_A_ADD0")
			(options
				(clearance outline)
				(anchor circle)
			)
			(primitives
				(gr_poly
					(pts
						(arc
							(start -0.1778 -0.2794)
							(mid -0.249642 -0.249642)
							(end -0.2794 -0.1778)
						)
						(arc
							(start -0.2794 0.1778)
							(mid -0.249642 0.249642)
							(end -0.1778 0.2794)
						)
						(arc
							(start 0.1778 0.2794)
							(mid 0.249642 0.249642)
							(end 0.2794 0.1778)
						)
						(arc
							(start 0.2794 -0.1778)
							(mid 0.249642 -0.249642)
							(end 0.1778 -0.2794)
						)
					)
					(width 0)
					(fill yes)
				)
			)
		)
	)
	(footprint ""
		(layer "F.Cu")
		(at 218.214702 -329.061064)
		(property "Reference" "C513"
			(at 0 0 0)
			(layer "F.SilkS")
			(hide yes)
			(effects
				(font
					(size 1.27 1.27)
				)
			)
		)
		(property "Value" "SC22U25V6KX-2-GP-U"
			(at -2.860802 -5.279644 0)
			(unlocked yes)
			(layer "F.Fab")
			(hide yes)
			(effects
				(font
					(size 1.016 1.016)
					(thickness 0.1524)
				)
			)
		)
		(property "Device Type" "C1206-TO0D3H75"
			(at -2.860802 -6.803644 0)
			(unlocked yes)
			(layer "F.Fab")
			(hide yes)
			(effects
				(font
					(size 1.016 1.016)
					(thickness 0.1524)
				)
			)
		)
		(duplicate_pad_numbers_are_jumpers no)
		(fp_line
			(start -1.3081 -2.3749)
			(end 1.3081 -2.3749)
			(stroke
				(width 0.1524)
				(type default)
			)
			(layer "F.SilkS")
		)
		(fp_line
			(start -1.3081 2.3749)
			(end -1.3081 -2.3749)
			(stroke
				(width 0.1524)
				(type default)
			)
			(layer "F.SilkS")
		)
		(fp_line
			(start 1.3081 -2.3749)
			(end 1.3081 2.3749)
			(stroke
				(width 0.1524)
				(type default)
			)
			(layer "F.SilkS")
		)
		(fp_line
			(start 1.3081 2.3749)
			(end -1.3081 2.3749)
			(stroke
				(width 0.1524)
				(type default)
			)
			(layer "F.SilkS")
		)
		(fp_rect
			(start -0.8001 1.6002)
			(end 0.8001 -1.6002)
			(stroke
				(width 0)
				(type default)
			)
			(fill no)
			(layer "F.CrtYd")
		)
		(fp_poly
			(pts
				(xy -1.5621 2.4511) (xy -1.5621 1.6002) (xy 0.8001 1.6002) (xy 0.8001 -1.6002) (xy -0.8001 -1.6002)
				(xy -0.8001 1.5875) (xy -1.5621 1.5875) (xy -1.5621 -2.4511) (xy 1.5621 -2.4511) (xy 1.5621 2.4511)
			)
			(stroke
				(width 0)
				(type default)
			)
			(fill no)
			(layer "F.CrtYd")
		)
		(fp_rect
			(start -1.5621 2.4511)
			(end 1.5621 -2.4511)
			(stroke
				(width 0)
				(type default)
			)
			(fill no)
			(layer "F.Fab")
		)
		(pad "1" smd rect
			(at 0 -1.392936)
			(size 2.1082 1.4478)
			(layers "F.Cu" "F.Mask" "F.Paste")
			(net "P12V_IN")
		)
		(pad "2" smd rect
			(at 0 1.392936)
			(size 2.1082 1.4478)
			(layers "F.Cu" "F.Mask" "F.Paste")
			(net "GND")
		)
	)
	(footprint ""
		(layer "F.Cu")
		(at 413.866076 -269.705074)
		(property "Reference" "TP66"
			(at 0 0 0)
			(layer "F.SilkS")
			(hide yes)
			(effects
				(font
					(size 1.27 1.27)
				)
			)
		)
		(property "Value" "*"
			(at -0.0508 -1.6764 0)
			(unlocked yes)
			(layer "F.Fab")
			(hide yes)
			(effects
				(font
					(size 1.016 1.016)
					(thickness 0.1524)
				)
			)
		)
		(property "Device Type" "TPAD32"
			(at -0.0508 -3.2004 0)
			(unlocked yes)
			(layer "F.Fab")
			(hide yes)
			(effects
				(font
					(size 1.016 1.016)
					(thickness 0.1524)
				)
			)
		)
		(duplicate_pad_numbers_are_jumpers no)
		(fp_poly
			(pts
				(arc
					(start 0.4064 0)
					(mid -0.4064 0)
					(end 0.4064 0)
				)
			)
			(stroke
				(width 0)
				(type default)
			)
			(fill no)
			(layer "F.CrtYd")
		)
		(fp_poly
			(pts
				(arc
					(start 0.7112 0)
					(mid -0.7112 0)
					(end 0.7112 0)
				)
			)
			(stroke
				(width 0)
				(type default)
			)
			(fill no)
			(layer "F.Fab")
		)
		(pad "1" smd circle
			(at 0 0)
			(size 0.8128 0.8128)
			(layers "F.Cu" "F.Mask" "F.Paste")
			(net "ACT_HDD_9")
		)
	)
	(footprint ""
		(layer "F.Cu")
		(at 51.7652 -148.717 -90)
		(property "Reference" "C199"
			(at 0 0 270)
			(layer "F.SilkS")
			(hide yes)
			(effects
				(font
					(size 1.27 1.27)
				)
			)
		)
		(property "Value" "SC1U16V3KX-5GP"
			(at 0 -2.8194 270)
			(unlocked yes)
			(layer "F.Fab")
			(hide yes)
			(effects
				(font
					(size 1.016 1.016)
					(thickness 0.1524)
				)
			)
		)
		(property "Device Type" "C603H36"
			(at 0 -4.3434 270)
			(unlocked yes)
			(layer "F.Fab")
			(hide yes)
			(effects
				(font
					(size 1.016 1.016)
					(thickness 0.1524)
				)
			)
		)
		(duplicate_pad_numbers_are_jumpers no)
		(fp_line
			(start 0.508 0)
			(end -0.508 0)
			(stroke
				(width 0.2032)
				(type default)
			)
			(layer "F.SilkS")
		)
		(fp_rect
			(start -0.5842 1.3335)
			(end 0.5842 -1.3335)
			(stroke
				(width 0)
				(type default)
			)
			(fill no)
			(layer "F.CrtYd")
		)
		(fp_rect
			(start -0.5842 1.3335)
			(end 0.5842 -1.3335)
			(stroke
				(width 0)
				(type default)
			)
			(fill no)
			(layer "F.Fab")
		)
		(pad "1" smd custom
			(at 0 -0.762 270)
			(size 0.2159 0.2159)
			(layers "F.Cu" "F.Mask" "F.Paste")
			(net "P5V_HDD13")
			(options
				(clearance outline)
				(anchor circle)
			)
			(primitives
				(gr_poly
					(pts
						(arc
							(start -0.3302 -0.4318)
							(mid -0.402042 -0.402042)
							(end -0.4318 -0.3302)
						)
						(arc
							(start -0.4318 0.3302)
							(mid -0.402042 0.402042)
							(end -0.3302 0.4318)
						)
						(arc
							(start 0.3302 0.4318)
							(mid 0.402042 0.402042)
							(end 0.4318 0.3302)
						)
						(arc
							(start 0.4318 -0.3302)
							(mid 0.402042 -0.402042)
							(end 0.3302 -0.4318)
						)
					)
					(width 0)
					(fill yes)
				)
			)
		)
		(pad "2" smd custom
			(at 0 0.762 270)
			(size 0.2159 0.2159)
			(layers "F.Cu" "F.Mask" "F.Paste")
			(net "GND")
			(options
				(clearance outline)
				(anchor circle)
			)
			(primitives
				(gr_poly
					(pts
						(arc
							(start -0.3302 -0.4318)
							(mid -0.402042 -0.402042)
							(end -0.4318 -0.3302)
						)
						(arc
							(start -0.4318 0.3302)
							(mid -0.402042 0.402042)
							(end -0.3302 0.4318)
						)
						(arc
							(start 0.3302 0.4318)
							(mid 0.402042 0.402042)
							(end 0.4318 0.3302)
						)
						(arc
							(start 0.4318 -0.3302)
							(mid 0.402042 -0.402042)
							(end 0.3302 -0.4318)
						)
					)
					(width 0)
					(fill yes)
				)
			)
		)
	)
	(footprint ""
		(layer "F.Cu")
		(at 47.173388 -118.778274 90)
		(property "Reference" "R1128"
			(at 0 0 90)
			(layer "F.SilkS")
			(hide yes)
			(effects
				(font
					(size 1.27 1.27)
				)
			)
		)
		(property "Value" "100KR2F-L1-GP"
			(at 0.064008 -3.993896 90)
			(unlocked yes)
			(layer "F.Fab")
			(hide yes)
			(effects
				(font
					(size 1.016 1.016)
					(thickness 0.1524)
				)
			)
		)
		(property "Device Type" "R402H16"
			(at 0.064008 -5.517896 90)
			(unlocked yes)
			(layer "F.Fab")
			(hide yes)
			(effects
				(font
					(size 1.016 1.016)
					(thickness 0.1524)
				)
			)
		)
		(duplicate_pad_numbers_are_jumpers no)
		(fp_line
			(start 0.508 -0.9398)
			(end -0.508 -0.9398)
			(stroke
				(width 0.1524)
				(type default)
			)
			(layer "F.SilkS")
		)
		(fp_line
			(start -0.508 -0.9398)
			(end -0.508 0.9398)
			(stroke
				(width 0.1524)
				(type default)
			)
			(layer "F.SilkS")
		)
		(fp_rect
			(start -0.508 0.9398)
			(end 0.508 -0.9398)
			(stroke
				(width 0)
				(type default)
			)
			(fill no)
			(layer "F.CrtYd")
		)
		(fp_rect
			(start -0.508 0.9398)
			(end 0.508 -0.9398)
			(stroke
				(width 0)
				(type default)
			)
			(fill no)
			(layer "F.Fab")
		)
		(pad "1" smd custom
			(at 0 -0.4445 90)
			(size 0.1397 0.1397)
			(layers "F.Cu" "F.Mask" "F.Paste")
			(net "AGND_P5V_B_2")
			(options
				(clearance outline)
				(anchor circle)
			)
			(primitives
				(gr_poly
					(pts
						(arc
							(start -0.1778 -0.2794)
							(mid -0.249642 -0.249642)
							(end -0.2794 -0.1778)
						)
						(arc
							(start -0.2794 0.1778)
							(mid -0.249642 0.249642)
							(end -0.1778 0.2794)
						)
						(arc
							(start 0.1778 0.2794)
							(mid 0.249642 0.249642)
							(end 0.2794 0.1778)
						)
						(arc
							(start 0.2794 -0.1778)
							(mid 0.249642 -0.249642)
							(end 0.1778 -0.2794)
						)
					)
					(width 0)
					(fill yes)
				)
			)
		)
		(pad "2" smd custom
			(at 0 0.4445 90)
			(size 0.1397 0.1397)
			(layers "F.Cu" "F.Mask" "F.Paste")
			(net "P5V_B_2_MODE")
			(options
				(clearance outline)
				(anchor circle)
			)
			(primitives
				(gr_poly
					(pts
						(arc
							(start -0.1778 -0.2794)
							(mid -0.249642 -0.249642)
							(end -0.2794 -0.1778)
						)
						(arc
							(start -0.2794 0.1778)
							(mid -0.249642 0.249642)
							(end -0.1778 0.2794)
						)
						(arc
							(start 0.1778 0.2794)
							(mid 0.249642 0.249642)
							(end 0.2794 0.1778)
						)
						(arc
							(start 0.2794 -0.1778)
							(mid 0.249642 -0.249642)
							(end 0.1778 -0.2794)
						)
					)
					(width 0)
					(fill yes)
				)
			)
		)
	)
	(footprint ""
		(layer "F.Cu")
		(at 447.834512 -15.219426 -90)
		(property "Reference" "C470"
			(at 0 0 270)
			(layer "F.SilkS")
			(hide yes)
			(effects
				(font
					(size 1.27 1.27)
				)
			)
		)
		(property "Value" "SCD01U16V1KX-GP"
			(at -2.8321 -1.7399 270)
			(unlocked yes)
			(layer "F.Fab")
			(hide yes)
			(effects
				(font
					(size 1.016 1.016)
					(thickness 0.1524)
				)
			)
		)
		(property "Device Type" "C0201H13"
			(at -2.8321 -3.2639 270)
			(unlocked yes)
			(layer "F.Fab")
			(hide yes)
			(effects
				(font
					(size 1.016 1.016)
					(thickness 0.1524)
				)
			)
		)
		(duplicate_pad_numbers_are_jumpers no)
		(fp_rect
			(start -0.2794 0.6477)
			(end 0.2794 -0.6477)
			(stroke
				(width 0)
				(type default)
			)
			(fill no)
			(layer "F.CrtYd")
		)
		(fp_rect
			(start -0.2794 0.6477)
			(end 0.2794 -0.6477)
			(stroke
				(width 0)
				(type default)
			)
			(fill no)
			(layer "F.Fab")
		)
		(pad "1" smd custom
			(at 0 -0.2794 270)
			(size 0.0762 0.0762)
			(layers "F.Cu" "F.Mask" "F.Paste")
			(net "SAS_HDD_RX_N34")
			(options
				(clearance outline)
				(anchor circle)
			)
			(primitives
				(gr_poly
					(pts
						(arc
							(start 0.1524 -0.127)
							(mid 0.137521 -0.162921)
							(end 0.1016 -0.1778)
						)
						(arc
							(start -0.1016 -0.1778)
							(mid -0.137521 -0.162921)
							(end -0.1524 -0.127)
						)
						(arc
							(start -0.1524 0.127)
							(mid -0.137521 0.162921)
							(end -0.1016 0.1778)
						)
						(arc
							(start 0.1016 0.1778)
							(mid 0.137521 0.162921)
							(end 0.1524 0.127)
						)
					)
					(width 0)
					(fill yes)
				)
			)
		)
		(pad "2" smd custom
			(at 0 0.2794 270)
			(size 0.0762 0.0762)
			(layers "F.Cu" "F.Mask" "F.Paste")
			(net "PHY_SCC_B_TO_DRV_B_34_DN")
			(options
				(clearance outline)
				(anchor circle)
			)
			(primitives
				(gr_poly
					(pts
						(arc
							(start 0.1524 -0.127)
							(mid 0.137521 -0.162921)
							(end 0.1016 -0.1778)
						)
						(arc
							(start -0.1016 -0.1778)
							(mid -0.137521 -0.162921)
							(end -0.1524 -0.127)
						)
						(arc
							(start -0.1524 0.127)
							(mid -0.137521 0.162921)
							(end -0.1016 0.1778)
						)
						(arc
							(start 0.1016 0.1778)
							(mid 0.137521 0.162921)
							(end 0.1524 0.127)
						)
					)
					(width 0)
					(fill yes)
				)
			)
		)
	)
)
